(kicad_pcb
	(version 20260206)
	(generator "pcbnew")
	(generator_version "10.0")
	(general
		(thickness 1.6)
		(legacy_teardrops no)
	)
	(paper "A4")
	(title_block
		(title "Wiwynn_Tioga_Pass_MB.brd")
		(comment 1 "Tioga Pass / footprints 2976-2982 of 4770")
	)
	(layers
		(0 "F.Cu" signal "TOP")
		(4 "In1.Cu" signal "L2GND")
		(6 "In2.Cu" signal "L3")
		(8 "In3.Cu" signal "L4GND")
		(10 "In4.Cu" signal "L5")
		(12 "In5.Cu" signal "L6GND")
		(14 "In6.Cu" signal "L7VCC")
		(16 "In7.Cu" signal "L8VCC")
		(18 "In8.Cu" signal "L9GND")
		(20 "In9.Cu" signal "L10")
		(22 "In10.Cu" signal "L11GND")
		(24 "In11.Cu" signal "L12")
		(26 "In12.Cu" signal "L13GND")
		(2 "B.Cu" signal "BOTTOM")
		(9 "F.Adhes" user "F.Adhesive")
		(11 "B.Adhes" user "B.Adhesive")
		(13 "F.Paste" user "Package Geometry/Pastemask Top")
		(15 "B.Paste" user "Package Geometry/Pastemask Bottom")
		(5 "F.SilkS" user "Ref Des/Silkscreen Top")
		(7 "B.SilkS" user "Ref Des/Silkscreen Bottom")
		(1 "F.Mask" user "Board Geometry/Soldermask Top")
		(3 "B.Mask" user "Board Geometry/Soldermask Bottom")
		(17 "Dwgs.User" user "User.Drawings")
		(19 "Cmts.User" user "User.Comments")
		(21 "Eco1.User" user "User.Eco1")
		(23 "Eco2.User" user "User.Eco2")
		(25 "Edge.Cuts" user "Board Geometry/Outline")
		(27 "Margin" user)
		(31 "F.CrtYd" user "Package Geometry/Place Bound Top")
		(29 "B.CrtYd" user "Package Geometry/Place Bound Bottom")
		(35 "F.Fab" user "Ref Des/Assembly Top")
		(33 "B.Fab" user "Ref Des/Assembly Bottom")
	)
	(footprint ""
		(layer "B.Cu")
		(at 499.442994 -40.624506)
		(property "Reference" "U25W8"
			(at 0 0 0)
			(layer "B.SilkS")
			(hide yes)
			(effects
				(font
					(size 1.27 1.27)
				)
				(justify mirror)
			)
		)
		(property "Value" "*"
			(at 0 -10.7315 0)
			(unlocked yes)
			(layer "B.Fab")
			(hide yes)
			(effects
				(font
					(size 1.27 1.016)
					(thickness 0.1524)
				)
				(justify mirror)
			)
		)
		(property "Device Type" "U74AHCT1G125G-AL5-R-GP-U_TTL-GA"
			(at 0 -12.2555 0)
			(unlocked yes)
			(layer "B.Fab")
			(hide yes)
			(effects
				(font
					(size 1.27 1.016)
					(thickness 0.1524)
				)
				(justify mirror)
			)
		)
		(duplicate_pad_numbers_are_jumpers no)
		(fp_line
			(start -1.24714 -1.79832)
			(end -1.24714 1.82372)
			(stroke
				(width 0.1524)
				(type default)
			)
			(layer "B.SilkS")
		)
		(fp_line
			(start -1.2446 1.81102)
			(end -1.25476 1.82118)
			(stroke
				(width 0.1524)
				(type default)
			)
			(layer "B.SilkS")
		)
		(fp_line
			(start -1.08712 -1.80848)
			(end 1.23952 -1.80848)
			(stroke
				(width 0.1524)
				(type default)
			)
			(layer "B.SilkS")
		)
		(fp_line
			(start -1.08204 -1.80848)
			(end -1.26492 -1.80848)
			(stroke
				(width 0.1524)
				(type default)
			)
			(layer "B.SilkS")
		)
		(fp_line
			(start -1.08204 1.81102)
			(end 1.4859 1.81102)
			(stroke
				(width 0.1524)
				(type default)
			)
			(layer "B.SilkS")
		)
		(fp_line
			(start -1.06934 1.81102)
			(end -1.2446 1.81102)
			(stroke
				(width 0.1524)
				(type default)
			)
			(layer "B.SilkS")
		)
		(fp_line
			(start 1.2446 1.8034)
			(end 1.2446 -1.8161)
			(stroke
				(width 0.1524)
				(type default)
			)
			(layer "B.SilkS")
		)
		(fp_line
			(start 1.3081 0.49022)
			(end 1.3081 1.7907)
			(stroke
				(width 0.508)
				(type default)
			)
			(layer "B.SilkS")
		)
		(fp_poly
			(pts
				(xy 0.82804 0.10922) (xy -0.82804 0.10922) (xy -0.82804 -0.10795) (xy 0.82804 -0.10795)
			)
			(stroke
				(width 0)
				(type default)
			)
			(fill yes)
			(layer "B.SilkS")
		)
		(fp_poly
			(pts
				(xy 1.5621 2.0447) (xy -1.5621 2.0447) (xy -1.5621 -2.0447) (xy 1.5621 -2.0447)
			)
			(stroke
				(width 0)
				(type default)
			)
			(fill no)
			(layer "B.CrtYd")
		)
		(fp_poly
			(pts
				(xy 1.5621 -2.0447) (xy -1.5621 -2.0447) (xy -1.5621 2.0447) (xy 1.5621 2.0447)
			)
			(stroke
				(width 0)
				(type default)
			)
			(fill no)
			(layer "B.Fab")
		)
		(pad "1" smd rect
			(at 0.65024 0.92202 180)
			(size 0.3556 1.2192)
			(layers "B.Cu" "B.Mask" "B.Paste")
			(net "GND")
		)
		(pad "2" smd rect
			(at 0 0.92202 180)
			(size 0.3556 1.2192)
			(layers "B.Cu" "B.Mask" "B.Paste")
			(net "BMC_VGA_VSYNC")
		)
		(pad "3" smd rect
			(at -0.65024 0.92202 180)
			(size 0.3556 1.2192)
			(layers "B.Cu" "B.Mask" "B.Paste")
			(net "GND")
		)
		(pad "4" smd rect
			(at -0.65024 -0.92075 180)
			(size 0.3556 1.2192)
			(layers "B.Cu" "B.Mask" "B.Paste")
			(net "VGA_REAR_VSYNC_S")
		)
		(pad "5" smd rect
			(at 0.65024 -0.92075 180)
			(size 0.3556 1.2192)
			(layers "B.Cu" "B.Mask" "B.Paste")
			(net "P5V_VGA_D")
		)
	)
	(footprint ""
		(layer "B.Cu")
		(at 4.70408 -13.52296 90)
		(property "Reference" "C1F21"
			(at 0 0 90)
			(layer "B.SilkS")
			(hide yes)
			(effects
				(font
					(size 1.27 1.27)
				)
				(justify mirror)
			)
		)
		(property "Value" "*"
			(at -1.1811 -2.8194 90)
			(unlocked yes)
			(layer "B.Fab")
			(hide yes)
			(effects
				(font
					(size 1.27 1.016)
					(thickness 0.1524)
				)
				(justify mirror)
			)
		)
		(property "Device Type" "SC1U10V2KX-4-GP_SMD-BCG6-SC1U1A"
			(at -1.1811 -4.3434 90)
			(unlocked yes)
			(layer "B.Fab")
			(hide yes)
			(effects
				(font
					(size 1.27 1.016)
					(thickness 0.1524)
				)
				(justify mirror)
			)
		)
		(duplicate_pad_numbers_are_jumpers no)
		(fp_rect
			(start 0.4318 0.9525)
			(end -0.4318 -0.9525)
			(stroke
				(width 0)
				(type default)
			)
			(fill no)
			(layer "B.CrtYd")
		)
		(fp_rect
			(start 0.4318 0.9525)
			(end -0.4318 -0.9525)
			(stroke
				(width 0)
				(type default)
			)
			(fill no)
			(layer "B.Fab")
		)
		(pad "1" smd custom
			(at 0 -0.4445 270)
			(size 0.1524 0.1524)
			(layers "B.Cu" "B.Mask" "B.Paste")
			(net "P5V_STBY")
			(options
				(clearance outline)
				(anchor circle)
			)
			(primitives
				(gr_poly
					(pts
						(arc
							(start 0.3048 0.2032)
							(mid 0.275042 0.275042)
							(end 0.2032 0.3048)
						)
						(arc
							(start -0.2032 0.3048)
							(mid -0.275042 0.275042)
							(end -0.3048 0.2032)
						)
						(arc
							(start -0.3048 -0.2032)
							(mid -0.275042 -0.275042)
							(end -0.2032 -0.3048)
						)
						(arc
							(start 0.2032 -0.3048)
							(mid 0.275042 -0.275042)
							(end 0.3048 -0.2032)
						)
					)
					(width 0)
					(fill yes)
				)
			)
		)
		(pad "2" smd custom
			(at 0 0.4445 270)
			(size 0.1524 0.1524)
			(layers "B.Cu" "B.Mask" "B.Paste")
			(net "GND")
			(options
				(clearance outline)
				(anchor circle)
			)
			(primitives
				(gr_poly
					(pts
						(arc
							(start 0.3048 0.2032)
							(mid 0.275042 0.275042)
							(end 0.2032 0.3048)
						)
						(arc
							(start -0.2032 0.3048)
							(mid -0.275042 0.275042)
							(end -0.3048 0.2032)
						)
						(arc
							(start -0.3048 -0.2032)
							(mid -0.275042 -0.275042)
							(end -0.2032 -0.3048)
						)
						(arc
							(start 0.2032 -0.3048)
							(mid 0.275042 -0.275042)
							(end 0.3048 -0.2032)
						)
					)
					(width 0)
					(fill yes)
				)
			)
		)
	)
	(footprint ""
		(layer "B.Cu")
		(at 411.0355 -129.413 90)
		(property "Reference" "C2M2"
			(at 0 0 90)
			(layer "B.SilkS")
			(hide yes)
			(effects
				(font
					(size 1.27 1.27)
				)
				(justify mirror)
			)
		)
		(property "Value" ""
			(at 0 0 90)
			(layer "B.Fab")
			(effects
				(font
					(size 1.27 1.27)
				)
				(justify mirror)
			)
		)
		(duplicate_pad_numbers_are_jumpers no)
		(fp_poly
			(pts
				(xy 0.4953 -0.2032) (xy -0.4953 -0.2032) (xy -0.4953 1.6002) (xy 0.4953 1.6002)
			)
			(stroke
				(width 0)
				(type default)
			)
			(fill no)
			(layer "B.CrtYd")
		)
		(fp_line
			(start 0.4953 -0.2032)
			(end -0.4953 -0.2032)
			(stroke
				(width 0.1)
				(type default)
			)
			(layer "B.Fab")
		)
		(fp_line
			(start -0.4953 -0.2032)
			(end -0.4953 1.6002)
			(stroke
				(width 0.1)
				(type default)
			)
			(layer "B.Fab")
		)
		(fp_line
			(start 0.4953 1.6002)
			(end 0.4953 -0.2032)
			(stroke
				(width 0.1)
				(type default)
			)
			(layer "B.Fab")
		)
		(fp_line
			(start -0.4953 1.6002)
			(end 0.4953 1.6002)
			(stroke
				(width 0.1)
				(type default)
			)
			(layer "B.Fab")
		)
		(pad "1" smd rect
			(at 0 0 270)
			(size 0.762 0.889)
			(layers "B.Cu" "B.Mask" "B.Paste")
			(net "P1V8_PCH_STBY")
		)
		(pad "2" smd rect
			(at 0 1.397 270)
			(size 0.762 0.889)
			(layers "B.Cu" "B.Mask" "B.Paste")
			(net "GND")
		)
		(zone
			(layer "B.Cu")
			(hatch none 0.5)
			(connect_pads
				(clearance 0)
			)
			(min_thickness 0.25)
			(keepout
				(tracks not_allowed)
				(vias allowed)
				(pads allowed)
				(copperpour not_allowed)
				(footprints allowed)
			)
			(placement
				(enabled no)
				(sheetname "")
			)
			(fill
				(thermal_gap 0.5)
				(thermal_bridge_width 0.5)
				(island_removal_mode 0)
			)
			(polygon
				(pts
					(xy 411.48 -129.794) (xy 411.48 -129.032) (xy 411.988 -129.032) (xy 411.988 -129.794)
				)
			)
		)
	)
	(footprint ""
		(layer "B.Cu")
		(at 404.913846 -26.489152)
		(property "Reference" "C9G20"
			(at 0 0 0)
			(layer "B.SilkS")
			(hide yes)
			(effects
				(font
					(size 1.27 1.27)
				)
				(justify mirror)
			)
		)
		(property "Value" ""
			(at 0 0 0)
			(layer "B.Fab")
			(effects
				(font
					(size 1.27 1.27)
				)
				(justify mirror)
			)
		)
		(duplicate_pad_numbers_are_jumpers no)
		(fp_poly
			(pts
				(xy -0.3048 -0.1016) (xy -0.3048 0.9906) (xy 0.3048 0.9906) (xy 0.3048 -0.1016)
			)
			(stroke
				(width 0)
				(type default)
			)
			(fill no)
			(layer "B.CrtYd")
		)
		(fp_line
			(start -0.3048 -0.1016)
			(end 0.3048 -0.1016)
			(stroke
				(width 0.1)
				(type default)
			)
			(layer "B.Fab")
		)
		(fp_line
			(start -0.3048 0.9906)
			(end -0.3048 -0.1016)
			(stroke
				(width 0.1)
				(type default)
			)
			(layer "B.Fab")
		)
		(fp_line
			(start 0.3048 -0.1016)
			(end 0.3048 0.9906)
			(stroke
				(width 0.1)
				(type default)
			)
			(layer "B.Fab")
		)
		(fp_line
			(start 0.3048 0.9906)
			(end -0.3048 0.9906)
			(stroke
				(width 0.1)
				(type default)
			)
			(layer "B.Fab")
		)
		(pad "1" smd rect
			(at 0 0 180)
			(size 0.508 0.508)
			(layers "B.Cu" "B.Mask" "B.Paste")
			(net "A_P3V3_STBY_SCALED")
		)
		(pad "2" smd rect
			(at 0 0.889 180)
			(size 0.508 0.508)
			(layers "B.Cu" "B.Mask" "B.Paste")
			(net "GND")
		)
		(zone
			(layer "B.Cu")
			(hatch none 0.5)
			(connect_pads
				(clearance 0)
			)
			(min_thickness 0.25)
			(keepout
				(tracks allowed)
				(vias not_allowed)
				(pads allowed)
				(copperpour not_allowed)
				(footprints allowed)
			)
			(placement
				(enabled no)
				(sheetname "")
			)
			(fill
				(thermal_gap 0.5)
				(thermal_bridge_width 0.5)
				(island_removal_mode 0)
			)
			(polygon
				(pts
					(xy 405.167846 -26.235152) (xy 404.659846 -26.235152) (xy 404.659846 -25.854152) (xy 405.167846 -25.854152)
				)
			)
		)
		(zone
			(layer "B.Cu")
			(hatch none 0.5)
			(connect_pads
				(clearance 0)
			)
			(min_thickness 0.25)
			(keepout
				(tracks not_allowed)
				(vias allowed)
				(pads allowed)
				(copperpour not_allowed)
				(footprints allowed)
			)
			(placement
				(enabled no)
				(sheetname "")
			)
			(fill
				(thermal_gap 0.5)
				(thermal_bridge_width 0.5)
				(island_removal_mode 0)
			)
			(polygon
				(pts
					(xy 405.167846 -25.854152) (xy 404.659846 -25.854152) (xy 404.659846 -26.235152) (xy 405.167846 -26.235152)
				)
			)
		)
	)
	(footprint ""
		(layer "B.Cu")
		(at 418.6936 -15.296134 180)
		(property "Reference" "Q2T2"
			(at 1.26873 2.4638 90)
			(unlocked yes)
			(layer "B.SilkS")
			(effects
				(font
					(size 0.7874 0.5842)
					(thickness 0.1524)
				)
				(justify left mirror)
			)
		)
		(property "Value" ""
			(at 0 0 0)
			(layer "B.Fab")
			(effects
				(font
					(size 1.27 1.27)
				)
				(justify mirror)
			)
		)
		(duplicate_pad_numbers_are_jumpers no)
		(fp_line
			(start -0.381 0.635)
			(end -0.381 1.27)
			(stroke
				(width 0.1524)
				(type default)
			)
			(layer "B.SilkS")
		)
		(fp_line
			(start -0.9525 2.4765)
			(end -1.778 2.4765)
			(stroke
				(width 0.1524)
				(type default)
			)
			(layer "B.SilkS")
		)
		(fp_line
			(start -0.9525 -0.5715)
			(end -1.778 -0.5715)
			(stroke
				(width 0.1524)
				(type default)
			)
			(layer "B.SilkS")
		)
		(fp_line
			(start -1.778 2.4765)
			(end -1.778 1.5875)
			(stroke
				(width 0.1524)
				(type default)
			)
			(layer "B.SilkS")
		)
		(fp_line
			(start -1.778 -0.5715)
			(end -1.778 0.3175)
			(stroke
				(width 0.1524)
				(type default)
			)
			(layer "B.SilkS")
		)
		(fp_circle
			(center 0.9525 -0.9271)
			(end 0.8255 -0.9271)
			(stroke
				(width 0.254)
				(type default)
			)
			(fill no)
			(layer "B.SilkS")
		)
		(fp_poly
			(pts
				(xy -1.778 2.4765) (xy -0.381 2.4765) (xy -0.381 -0.5715) (xy -1.778 -0.5715)
			)
			(stroke
				(width 0)
				(type default)
			)
			(fill no)
			(layer "B.CrtYd")
		)
		(fp_line
			(start -0.381 2.4765)
			(end -1.778 2.4765)
			(stroke
				(width 0.1)
				(type default)
			)
			(layer "B.Fab")
		)
		(fp_line
			(start -0.381 -0.5715)
			(end -0.381 2.4765)
			(stroke
				(width 0.1)
				(type default)
			)
			(layer "B.Fab")
		)
		(fp_line
			(start -1.778 2.4765)
			(end -1.778 -0.5715)
			(stroke
				(width 0.1)
				(type default)
			)
			(layer "B.Fab")
		)
		(fp_line
			(start -1.778 -0.5715)
			(end -0.381 -0.5715)
			(stroke
				(width 0.1)
				(type default)
			)
			(layer "B.Fab")
		)
		(fp_circle
			(center 0.9525 -0.9271)
			(end 0.8255 -0.9271)
			(stroke
				(width 0.254)
				(type default)
			)
			(fill no)
			(layer "B.Fab")
		)
		(pad "1" smd rect
			(at 0 0)
			(size 1.143 0.508)
			(layers "B.Cu" "B.Mask" "B.Paste")
			(net "H_CPU0_FAST_WAKE")
		)
		(pad "2" smd rect
			(at 0 1.905)
			(size 1.143 0.508)
			(layers "B.Cu" "B.Mask" "B.Paste")
			(net "GND")
		)
		(pad "3" smd rect
			(at -2.159 0.9525)
			(size 1.143 0.508)
			(layers "B.Cu" "B.Mask" "B.Paste")
			(net "H_CPU0_FAST_WAKE_LVT3_N")
		)
	)
	(footprint ""
		(layer "B.Cu")
		(at 32.2834 -87.0204 90)
		(property "Reference" "R9P32"
			(at 0 0 90)
			(layer "B.SilkS")
			(hide yes)
			(effects
				(font
					(size 1.27 1.27)
				)
				(justify mirror)
			)
		)
		(property "Value" ""
			(at 0 0 90)
			(layer "B.Fab")
			(effects
				(font
					(size 1.27 1.27)
				)
				(justify mirror)
			)
		)
		(duplicate_pad_numbers_are_jumpers no)
		(fp_poly
			(pts
				(xy 0.2794 -0.1016) (xy -0.2794 -0.1016) (xy -0.2794 0.9906) (xy 0.2794 0.9906)
			)
			(stroke
				(width 0)
				(type default)
			)
			(fill no)
			(layer "B.CrtYd")
		)
		(fp_line
			(start 0.2794 -0.1016)
			(end 0.2794 0.9906)
			(stroke
				(width 0.1)
				(type default)
			)
			(layer "B.Fab")
		)
		(fp_line
			(start -0.2794 -0.1016)
			(end 0.2794 -0.1016)
			(stroke
				(width 0.1)
				(type default)
			)
			(layer "B.Fab")
		)
		(fp_line
			(start 0.2794 0.9906)
			(end -0.2794 0.9906)
			(stroke
				(width 0.1)
				(type default)
			)
			(layer "B.Fab")
		)
		(fp_line
			(start -0.2794 0.9906)
			(end -0.2794 -0.1016)
			(stroke
				(width 0.1)
				(type default)
			)
			(layer "B.Fab")
		)
		(pad "1" smd rect
			(at 0 0 270)
			(size 0.508 0.508)
			(layers "B.Cu" "B.Mask" "B.Paste")
			(net "VR_PVCCIN_CPU1_PH5_VCIN")
		)
		(pad "2" smd rect
			(at 0 0.889 270)
			(size 0.508 0.508)
			(layers "B.Cu" "B.Mask" "B.Paste")
			(net "P5V_STBY")
		)
		(zone
			(layer "B.Cu")
			(hatch none 0.5)
			(connect_pads
				(clearance 0)
			)
			(min_thickness 0.25)
			(keepout
				(tracks allowed)
				(vias not_allowed)
				(pads allowed)
				(copperpour not_allowed)
				(footprints allowed)
			)
			(placement
				(enabled no)
				(sheetname "")
			)
			(fill
				(thermal_gap 0.5)
				(thermal_bridge_width 0.5)
				(island_removal_mode 0)
			)
			(polygon
				(pts
					(xy 32.5374 -87.2744) (xy 32.5374 -86.7664) (xy 32.9184 -86.7664) (xy 32.9184 -87.2744)
				)
			)
		)
		(zone
			(layer "B.Cu")
			(hatch none 0.5)
			(connect_pads
				(clearance 0)
			)
			(min_thickness 0.25)
			(keepout
				(tracks not_allowed)
				(vias allowed)
				(pads allowed)
				(copperpour not_allowed)
				(footprints allowed)
			)
			(placement
				(enabled no)
				(sheetname "")
			)
			(fill
				(thermal_gap 0.5)
				(thermal_bridge_width 0.5)
				(island_removal_mode 0)
			)
			(polygon
				(pts
					(xy 32.9184 -87.2744) (xy 32.9184 -86.7664) (xy 32.5374 -86.7664) (xy 32.5374 -87.2744)
				)
			)
		)
	)
	(footprint ""
		(layer "B.Cu")
		(at 391.3251 -64.381888 180)
		(property "Reference" "U2T2"
			(at 0.67564 -2.27203 180)
			(unlocked yes)
			(layer "B.SilkS")
			(effects
				(font
					(size 0.7874 0.5842)
					(thickness 0.1524)
				)
				(justify left mirror)
			)
		)
		(property "Value" ""
			(at 0 0 0)
			(layer "B.Fab")
			(effects
				(font
					(size 1.27 1.27)
				)
				(justify mirror)
			)
		)
		(duplicate_pad_numbers_are_jumpers no)
		(fp_circle
			(center 0.4699 -0.8382)
			(end 0.3429 -0.8382)
			(stroke
				(width 0.254)
				(type default)
			)
			(fill no)
			(layer "B.SilkS")
		)
		(fp_poly
			(pts
				(xy -0.21463 -0.450088) (xy -1.56337 -0.450088) (xy -1.56337 1.75006) (xy -0.21463 1.75006)
			)
			(stroke
				(width 0)
				(type default)
			)
			(fill no)
			(layer "B.CrtYd")
		)
		(fp_line
			(start -0.21463 1.75006)
			(end -0.21463 -0.450088)
			(stroke
				(width 0.1)
				(type default)
			)
			(layer "B.Fab")
		)
		(fp_line
			(start -0.21463 -0.450088)
			(end -1.56337 -0.450088)
			(stroke
				(width 0.1)
				(type default)
			)
			(layer "B.Fab")
		)
		(fp_line
			(start -1.56337 1.75006)
			(end -0.21463 1.75006)
			(stroke
				(width 0.1)
				(type default)
			)
			(layer "B.Fab")
		)
		(fp_line
			(start -1.56337 -0.450088)
			(end -1.56337 1.75006)
			(stroke
				(width 0.1)
				(type default)
			)
			(layer "B.Fab")
		)
		(fp_circle
			(center 0.4699 -0.8382)
			(end 0.3429 -0.8382)
			(stroke
				(width 0.254)
				(type default)
			)
			(fill no)
			(layer "B.Fab")
		)
		(pad "1" smd rect
			(at 0 0)
			(size 1.016 0.381)
			(layers "B.Cu" "B.Mask" "B.Paste")
			(net "FM_BACKUP_BIOS_SEL_N")
		)
		(pad "2" smd rect
			(at 0 0.649986)
			(size 1.016 0.381)
			(layers "B.Cu" "B.Mask" "B.Paste")
			(net "SPI_SWITCH_CS0_N")
		)
		(pad "3" smd rect
			(at 0 1.299972)
			(size 1.016 0.381)
			(layers "B.Cu" "B.Mask" "B.Paste")
			(net "GND")
		)
		(pad "4" smd rect
			(at -1.778 1.299972)
			(size 1.016 0.381)
			(layers "B.Cu" "B.Mask" "B.Paste")
			(net "SPI_CS0_SECONDARY_N")
		)
		(pad "5" smd rect
			(at -1.778 0)
			(size 1.016 0.381)
			(layers "B.Cu" "B.Mask" "B.Paste")
			(net "P3V3_STBY")
		)
	)
)
